# T6G (Grand Teton) — schematic netlist excerpt (pin names and nets, part order shuffled) for the footprints in the layout excerpt that follows; sources: Cadence DE-HDL packaged netlist, KiCad conversion of 04192023_DAF0TMB3IC0_F0TG_MB_C_brd_V02_OCP.brd

PC436_8  Q_CAP  0.1UF 25V 10% X7R  pkg 0402  page 222 : A = PVDDCR_CPU1_P1_VCCS ; B = GND
C309  Q_CAP  10PF 50V 5% EMPTY  pkg 0402  page 217 : A = SVID_PVDDCR_CPU1_P1_SVD_R ; B = GND

(kicad_pcb
	(version 20260206)
	(generator "pcbnew")
	(generator_version "10.0")
	(general
		(thickness 1.6)
		(legacy_teardrops no)
	)
	(paper "A4")
	(title_block
		(title "04192023_DAF0TMB3IC0_F0TG_MB_C_brd_V02_OCP.brd")
		(comment 1 "Grand Teton / footprints 3370-3371 of 8354")
	)
	(layers
		(0 "F.Cu" signal "TOP")
		(4 "In1.Cu" signal "GND")
		(6 "In2.Cu" signal "IN1")
		(8 "In3.Cu" signal "GND1")
		(10 "In4.Cu" signal "IN2")
		(12 "In5.Cu" signal "GND2")
		(14 "In6.Cu" signal "IN3")
		(16 "In7.Cu" signal "GND3")
		(18 "In8.Cu" signal "VCC")
		(20 "In9.Cu" signal "VCC1")
		(22 "In10.Cu" signal "GND4")
		(24 "In11.Cu" signal "IN4")
		(26 "In12.Cu" signal "GND5")
		(28 "In13.Cu" signal "IN5")
		(30 "In14.Cu" signal "GND6")
		(32 "In15.Cu" signal "IN6")
		(34 "In16.Cu" signal "GND7")
		(2 "B.Cu" signal "BOTTOM")
		(9 "F.Adhes" user "F.Adhesive")
		(11 "B.Adhes" user "B.Adhesive")
		(13 "F.Paste" user "Package Geometry/Pastemask Top")
		(15 "B.Paste" user "Package Geometry/Pastemask Bottom")
		(5 "F.SilkS" user "Ref Des/Silkscreen Top")
		(7 "B.SilkS" user "Ref Des/Silkscreen Bottom")
		(1 "F.Mask" user "Board Geometry/Soldermask Top")
		(3 "B.Mask" user "Board Geometry/Soldermask Bottom")
		(17 "Dwgs.User" user "User.Drawings")
		(19 "Cmts.User" user "User.Comments")
		(21 "Eco1.User" user "User.Eco1")
		(23 "Eco2.User" user "User.Eco2")
		(25 "Edge.Cuts" user "Board Geometry/Outline")
		(27 "Margin" user)
		(31 "F.CrtYd" user "Package Geometry/Place Bound Top")
		(29 "B.CrtYd" user "Package Geometry/Place Bound Bottom")
		(35 "F.Fab" user "Ref Des/Assembly Top")
		(33 "B.Fab" user "Ref Des/Assembly Bottom")
	)
	(footprint ""
		(layer "F.Cu")
		(at 42.49293 -351.578672 90)
		(property "Reference" "PC436_8"
			(at 0 0 90)
			(layer "F.SilkS")
			(hide yes)
			(effects
				(font
					(size 1.27 1.27)
				)
			)
		)
		(property "Value" ""
			(at 0 0 90)
			(layer "F.Fab")
			(effects
				(font
					(size 1.27 1.27)
				)
			)
		)
		(duplicate_pad_numbers_are_jumpers no)
		(fp_line
			(start 0.7874 -0.4064)
			(end 0.7874 0.4064)
			(stroke
				(width 0.1524)
				(type default)
			)
			(layer "F.SilkS")
		)
		(fp_line
			(start -0.7874 -0.4064)
			(end 0.7874 -0.4064)
			(stroke
				(width 0.1524)
				(type default)
			)
			(layer "F.SilkS")
		)
		(fp_line
			(start 0.7874 0.4064)
			(end -0.7874 0.4064)
			(stroke
				(width 0.1524)
				(type default)
			)
			(layer "F.SilkS")
		)
		(fp_line
			(start -0.7874 0.4064)
			(end -0.7874 -0.4064)
			(stroke
				(width 0.1524)
				(type default)
			)
			(layer "F.SilkS")
		)
		(fp_line
			(start -0.12065 -0.305054)
			(end -0.12065 -0.2794)
			(stroke
				(width 0.1)
				(type default)
			)
			(layer "F.Fab")
		)
		(fp_line
			(start -0.67945 -0.305054)
			(end -0.12065 -0.305054)
			(stroke
				(width 0.1)
				(type default)
			)
			(layer "F.Fab")
		)
		(fp_line
			(start 0.67945 -0.3048)
			(end 0.67945 0.3048)
			(stroke
				(width 0.1)
				(type default)
			)
			(layer "F.Fab")
		)
		(fp_line
			(start 0.12065 -0.3048)
			(end 0.67945 -0.3048)
			(stroke
				(width 0.1)
				(type default)
			)
			(layer "F.Fab")
		)
		(fp_line
			(start 0.12065 -0.2794)
			(end 0.12065 -0.3048)
			(stroke
				(width 0.1)
				(type default)
			)
			(layer "F.Fab")
		)
		(fp_line
			(start -0.12065 -0.2794)
			(end 0.12065 -0.2794)
			(stroke
				(width 0.1)
				(type default)
			)
			(layer "F.Fab")
		)
		(fp_line
			(start 0.120396 0.2794)
			(end -0.12065 0.2794)
			(stroke
				(width 0.1)
				(type default)
			)
			(layer "F.Fab")
		)
		(fp_line
			(start -0.12065 0.2794)
			(end -0.12065 0.3048)
			(stroke
				(width 0.1)
				(type default)
			)
			(layer "F.Fab")
		)
		(fp_line
			(start 0.67945 0.3048)
			(end 0.120396 0.3048)
			(stroke
				(width 0.1)
				(type default)
			)
			(layer "F.Fab")
		)
		(fp_line
			(start 0.120396 0.3048)
			(end 0.120396 0.2794)
			(stroke
				(width 0.1)
				(type default)
			)
			(layer "F.Fab")
		)
		(fp_line
			(start -0.12065 0.3048)
			(end -0.67945 0.3048)
			(stroke
				(width 0.1)
				(type default)
			)
			(layer "F.Fab")
		)
		(fp_line
			(start -0.67945 0.3048)
			(end -0.67945 -0.305054)
			(stroke
				(width 0.1)
				(type default)
			)
			(layer "F.Fab")
		)
		(pad "1" smd circle
			(at -0.40005 0 90)
			(size 0 0)
			(layers "F.Cu" "F.Mask" "F.Paste")
			(net "PVDDCR_CPU1_P1_VCCS")
		)
		(pad "2" smd circle
			(at 0.40005 0 90)
			(size 0 0)
			(layers "F.Cu" "F.Mask" "F.Paste")
			(net "GND")
		)
	)
	(footprint ""
		(layer "F.Cu")
		(at 22.479 -361.061 180)
		(property "Reference" "C309"
			(at 0 0 180)
			(layer "F.SilkS")
			(hide yes)
			(effects
				(font
					(size 1.27 1.27)
				)
			)
		)
		(property "Value" ""
			(at 0 0 180)
			(layer "F.Fab")
			(effects
				(font
					(size 1.27 1.27)
				)
			)
		)
		(duplicate_pad_numbers_are_jumpers no)
		(fp_line
			(start 0.7874 0.4064)
			(end -0.7874 0.4064)
			(stroke
				(width 0.1524)
				(type default)
			)
			(layer "F.SilkS")
		)
		(fp_line
			(start 0.7874 -0.4064)
			(end 0.7874 0.4064)
			(stroke
				(width 0.1524)
				(type default)
			)
			(layer "F.SilkS")
		)
		(fp_line
			(start -0.7874 0.4064)
			(end -0.7874 -0.4064)
			(stroke
				(width 0.1524)
				(type default)
			)
			(layer "F.SilkS")
		)
		(fp_line
			(start -0.7874 -0.4064)
			(end 0.7874 -0.4064)
			(stroke
				(width 0.1524)
				(type default)
			)
			(layer "F.SilkS")
		)
		(fp_line
			(start 0.67945 0.3048)
			(end 0.120396 0.3048)
			(stroke
				(width 0.1)
				(type default)
			)
			(layer "F.Fab")
		)
		(fp_line
			(start 0.67945 -0.3048)
			(end 0.67945 0.3048)
			(stroke
				(width 0.1)
				(type default)
			)
			(layer "F.Fab")
		)
		(fp_line
			(start 0.12065 -0.2794)
			(end 0.12065 -0.3048)
			(stroke
				(width 0.1)
				(type default)
			)
			(layer "F.Fab")
		)
		(fp_line
			(start 0.12065 -0.3048)
			(end 0.67945 -0.3048)
			(stroke
				(width 0.1)
				(type default)
			)
			(layer "F.Fab")
		)
		(fp_line
			(start 0.120396 0.3048)
			(end 0.120396 0.2794)
			(stroke
				(width 0.1)
				(type default)
			)
			(layer "F.Fab")
		)
		(fp_line
			(start 0.120396 0.2794)
			(end -0.12065 0.2794)
			(stroke
				(width 0.1)
				(type default)
			)
			(layer "F.Fab")
		)
		(fp_line
			(start -0.12065 0.3048)
			(end -0.67945 0.3048)
			(stroke
				(width 0.1)
				(type default)
			)
			(layer "F.Fab")
		)
		(fp_line
			(start -0.12065 0.2794)
			(end -0.12065 0.3048)
			(stroke
				(width 0.1)
				(type default)
			)
			(layer "F.Fab")
		)
		(fp_line
			(start -0.12065 -0.2794)
			(end 0.12065 -0.2794)
			(stroke
				(width 0.1)
				(type default)
			)
			(layer "F.Fab")
		)
		(fp_line
			(start -0.12065 -0.305054)
			(end -0.12065 -0.2794)
			(stroke
				(width 0.1)
				(type default)
			)
			(layer "F.Fab")
		)
		(fp_line
			(start -0.67945 0.3048)
			(end -0.67945 -0.305054)
			(stroke
				(width 0.1)
				(type default)
			)
			(layer "F.Fab")
		)
		(fp_line
			(start -0.67945 -0.305054)
			(end -0.12065 -0.305054)
			(stroke
				(width 0.1)
				(type default)
			)
			(layer "F.Fab")
		)
		(pad "1" smd circle
			(at -0.40005 0 180)
			(size 0 0)
			(layers "F.Cu" "F.Mask" "F.Paste")
			(net "SVID_PVDDCR_CPU1_P1_SVD_R")
		)
		(pad "2" smd circle
			(at 0.40005 0 180)
			(size 0 0)
			(layers "F.Cu" "F.Mask" "F.Paste")
			(net "GND")
		)
	)
)
